(kicad_pcb
	(version 20260206)
	(generator "pcbnew")
	(generator_version "10.0")
	(general
		(thickness 1.6)
		(legacy_teardrops no)
	)
	(paper "A4")
	(title_block
		(title "04192023_DAF0TMB3IC0_F0TG_MB_C_brd_V02_OCP.brd")
		(comment 1 "Grand Teton / footprints 5465-5471 of 8354")
	)
	(layers
		(0 "F.Cu" signal "TOP")
		(4 "In1.Cu" signal "GND")
		(6 "In2.Cu" signal "IN1")
		(8 "In3.Cu" signal "GND1")
		(10 "In4.Cu" signal "IN2")
		(12 "In5.Cu" signal "GND2")
		(14 "In6.Cu" signal "IN3")
		(16 "In7.Cu" signal "GND3")
		(18 "In8.Cu" signal "VCC")
		(20 "In9.Cu" signal "VCC1")
		(22 "In10.Cu" signal "GND4")
		(24 "In11.Cu" signal "IN4")
		(26 "In12.Cu" signal "GND5")
		(28 "In13.Cu" signal "IN5")
		(30 "In14.Cu" signal "GND6")
		(32 "In15.Cu" signal "IN6")
		(34 "In16.Cu" signal "GND7")
		(2 "B.Cu" signal "BOTTOM")
		(9 "F.Adhes" user "F.Adhesive")
		(11 "B.Adhes" user "B.Adhesive")
		(13 "F.Paste" user "Package Geometry/Pastemask Top")
		(15 "B.Paste" user "Package Geometry/Pastemask Bottom")
		(5 "F.SilkS" user "Ref Des/Silkscreen Top")
		(7 "B.SilkS" user "Ref Des/Silkscreen Bottom")
		(1 "F.Mask" user "Board Geometry/Soldermask Top")
		(3 "B.Mask" user "Board Geometry/Soldermask Bottom")
		(17 "Dwgs.User" user "User.Drawings")
		(19 "Cmts.User" user "User.Comments")
		(21 "Eco1.User" user "User.Eco1")
		(23 "Eco2.User" user "User.Eco2")
		(25 "Edge.Cuts" user "Board Geometry/Outline")
		(27 "Margin" user)
		(31 "F.CrtYd" user "Package Geometry/Place Bound Top")
		(29 "B.CrtYd" user "Package Geometry/Place Bound Bottom")
		(35 "F.Fab" user "Ref Des/Assembly Top")
		(33 "B.Fab" user "Ref Des/Assembly Bottom")
	)
	(footprint ""
		(layer "B.Cu")
		(at 353.517454 -269.30731)
		(property "Reference" "C2216"
			(at 0 0 0)
			(layer "B.SilkS")
			(hide yes)
			(effects
				(font
					(size 1.27 1.27)
				)
				(justify mirror)
			)
		)
		(property "Value" ""
			(at 0 0 0)
			(layer "B.Fab")
			(effects
				(font
					(size 1.27 1.27)
				)
				(justify mirror)
			)
		)
		(duplicate_pad_numbers_are_jumpers no)
		(fp_line
			(start -0.7874 -0.4064)
			(end -0.7874 0.4064)
			(stroke
				(width 0.1524)
				(type default)
			)
			(layer "B.SilkS")
		)
		(fp_line
			(start -0.7874 0.4064)
			(end 0.7874 0.4064)
			(stroke
				(width 0.1524)
				(type default)
			)
			(layer "B.SilkS")
		)
		(fp_line
			(start 0.7874 -0.4064)
			(end -0.7874 -0.4064)
			(stroke
				(width 0.1524)
				(type default)
			)
			(layer "B.SilkS")
		)
		(fp_line
			(start 0.7874 0.4064)
			(end 0.7874 -0.4064)
			(stroke
				(width 0.1524)
				(type default)
			)
			(layer "B.SilkS")
		)
		(fp_line
			(start -0.67945 -0.3048)
			(end -0.67945 0.3048)
			(stroke
				(width 0.1)
				(type default)
			)
			(layer "B.Fab")
		)
		(fp_line
			(start -0.67945 0.3048)
			(end -0.120396 0.3048)
			(stroke
				(width 0.1)
				(type default)
			)
			(layer "B.Fab")
		)
		(fp_line
			(start -0.12065 -0.3048)
			(end -0.67945 -0.3048)
			(stroke
				(width 0.1)
				(type default)
			)
			(layer "B.Fab")
		)
		(fp_line
			(start -0.12065 -0.2794)
			(end -0.12065 -0.3048)
			(stroke
				(width 0.1)
				(type default)
			)
			(layer "B.Fab")
		)
		(fp_line
			(start -0.120396 0.2794)
			(end 0.12065 0.2794)
			(stroke
				(width 0.1)
				(type default)
			)
			(layer "B.Fab")
		)
		(fp_line
			(start -0.120396 0.3048)
			(end -0.120396 0.2794)
			(stroke
				(width 0.1)
				(type default)
			)
			(layer "B.Fab")
		)
		(fp_line
			(start 0.12065 -0.305054)
			(end 0.12065 -0.2794)
			(stroke
				(width 0.1)
				(type default)
			)
			(layer "B.Fab")
		)
		(fp_line
			(start 0.12065 -0.2794)
			(end -0.12065 -0.2794)
			(stroke
				(width 0.1)
				(type default)
			)
			(layer "B.Fab")
		)
		(fp_line
			(start 0.12065 0.2794)
			(end 0.12065 0.3048)
			(stroke
				(width 0.1)
				(type default)
			)
			(layer "B.Fab")
		)
		(fp_line
			(start 0.12065 0.3048)
			(end 0.67945 0.3048)
			(stroke
				(width 0.1)
				(type default)
			)
			(layer "B.Fab")
		)
		(fp_line
			(start 0.67945 -0.305054)
			(end 0.12065 -0.305054)
			(stroke
				(width 0.1)
				(type default)
			)
			(layer "B.Fab")
		)
		(fp_line
			(start 0.67945 0.3048)
			(end 0.67945 -0.305054)
			(stroke
				(width 0.1)
				(type default)
			)
			(layer "B.Fab")
		)
		(pad "1" smd circle
			(at 0.40005 0 180)
			(size 0 0)
			(layers "B.Cu" "B.Mask" "B.Paste")
			(net "PVDDCR_CPU1_P0")
		)
		(pad "2" smd circle
			(at -0.40005 0 180)
			(size 0 0)
			(layers "B.Cu" "B.Mask" "B.Paste")
			(net "GND")
		)
	)
	(footprint ""
		(layer "B.Cu")
		(at 192.795906 -72.804528)
		(property "Reference" "C1827"
			(at 0 0 0)
			(layer "B.SilkS")
			(hide yes)
			(effects
				(font
					(size 1.27 1.27)
				)
				(justify mirror)
			)
		)
		(property "Value" ""
			(at 0 0 0)
			(layer "B.Fab")
			(effects
				(font
					(size 1.27 1.27)
				)
				(justify mirror)
			)
		)
		(duplicate_pad_numbers_are_jumpers no)
		(fp_line
			(start -0.7874 -0.4064)
			(end -0.7874 0.4064)
			(stroke
				(width 0.1524)
				(type default)
			)
			(layer "B.SilkS")
		)
		(fp_line
			(start -0.7874 0.4064)
			(end 0.7874 0.4064)
			(stroke
				(width 0.1524)
				(type default)
			)
			(layer "B.SilkS")
		)
		(fp_line
			(start 0.7874 -0.4064)
			(end -0.7874 -0.4064)
			(stroke
				(width 0.1524)
				(type default)
			)
			(layer "B.SilkS")
		)
		(fp_line
			(start 0.7874 0.4064)
			(end 0.7874 -0.4064)
			(stroke
				(width 0.1524)
				(type default)
			)
			(layer "B.SilkS")
		)
		(fp_line
			(start -0.67945 -0.3048)
			(end -0.67945 0.3048)
			(stroke
				(width 0.1)
				(type default)
			)
			(layer "B.Fab")
		)
		(fp_line
			(start -0.67945 0.3048)
			(end -0.120396 0.3048)
			(stroke
				(width 0.1)
				(type default)
			)
			(layer "B.Fab")
		)
		(fp_line
			(start -0.12065 -0.3048)
			(end -0.67945 -0.3048)
			(stroke
				(width 0.1)
				(type default)
			)
			(layer "B.Fab")
		)
		(fp_line
			(start -0.12065 -0.2794)
			(end -0.12065 -0.3048)
			(stroke
				(width 0.1)
				(type default)
			)
			(layer "B.Fab")
		)
		(fp_line
			(start -0.120396 0.2794)
			(end 0.12065 0.2794)
			(stroke
				(width 0.1)
				(type default)
			)
			(layer "B.Fab")
		)
		(fp_line
			(start -0.120396 0.3048)
			(end -0.120396 0.2794)
			(stroke
				(width 0.1)
				(type default)
			)
			(layer "B.Fab")
		)
		(fp_line
			(start 0.12065 -0.305054)
			(end 0.12065 -0.2794)
			(stroke
				(width 0.1)
				(type default)
			)
			(layer "B.Fab")
		)
		(fp_line
			(start 0.12065 -0.2794)
			(end -0.12065 -0.2794)
			(stroke
				(width 0.1)
				(type default)
			)
			(layer "B.Fab")
		)
		(fp_line
			(start 0.12065 0.2794)
			(end 0.12065 0.3048)
			(stroke
				(width 0.1)
				(type default)
			)
			(layer "B.Fab")
		)
		(fp_line
			(start 0.12065 0.3048)
			(end 0.67945 0.3048)
			(stroke
				(width 0.1)
				(type default)
			)
			(layer "B.Fab")
		)
		(fp_line
			(start 0.67945 -0.305054)
			(end 0.12065 -0.305054)
			(stroke
				(width 0.1)
				(type default)
			)
			(layer "B.Fab")
		)
		(fp_line
			(start 0.67945 0.3048)
			(end 0.67945 -0.305054)
			(stroke
				(width 0.1)
				(type default)
			)
			(layer "B.Fab")
		)
		(pad "1" smd circle
			(at 0.40005 0 180)
			(size 0 0)
			(layers "B.Cu" "B.Mask" "B.Paste")
			(net "P3V3_AUX")
		)
		(pad "2" smd circle
			(at -0.40005 0 180)
			(size 0 0)
			(layers "B.Cu" "B.Mask" "B.Paste")
			(net "GND")
		)
	)
	(footprint ""
		(layer "B.Cu")
		(at 393.843002 -416.899344 90)
		(property "Reference" "C6612"
			(at 0 0 90)
			(layer "B.SilkS")
			(hide yes)
			(effects
				(font
					(size 1.27 1.27)
				)
				(justify mirror)
			)
		)
		(property "Value" ""
			(at 0 0 90)
			(layer "B.Fab")
			(effects
				(font
					(size 1.27 1.27)
				)
				(justify mirror)
			)
		)
		(duplicate_pad_numbers_are_jumpers no)
		(fp_line
			(start 0.299974 -0.150114)
			(end -0.299974 -0.150114)
			(stroke
				(width 0.1)
				(type default)
			)
			(layer "B.Fab")
		)
		(fp_line
			(start -0.299974 -0.150114)
			(end -0.299974 0.150114)
			(stroke
				(width 0.1)
				(type default)
			)
			(layer "B.Fab")
		)
		(fp_line
			(start 0.299974 0.150114)
			(end 0.299974 -0.150114)
			(stroke
				(width 0.1)
				(type default)
			)
			(layer "B.Fab")
		)
		(fp_line
			(start -0.299974 0.150114)
			(end 0.299974 0.150114)
			(stroke
				(width 0.1)
				(type default)
			)
			(layer "B.Fab")
		)
		(pad "1" smd rect
			(at 0.2667 0 270)
			(size 0.3048 0.381)
			(layers "B.Cu" "B.Mask" "B.Paste")
			(net "P5E_CPU0_P3_TX_BUF_C_DN<7>")
		)
		(pad "2" smd rect
			(at -0.2667 0 270)
			(size 0.3048 0.381)
			(layers "B.Cu" "B.Mask" "B.Paste")
			(net "P5E_CPU0_P3_TX_BUF_DN<7>")
		)
	)
	(footprint ""
		(layer "B.Cu")
		(at 95.064072 -477.345502)
		(property "Reference" "ME7"
			(at 0 0 0)
			(layer "B.SilkS")
			(hide yes)
			(effects
				(font
					(size 1.27 1.27)
				)
				(justify mirror)
			)
		)
		(property "Value" ""
			(at 0 0 0)
			(layer "B.Fab")
			(effects
				(font
					(size 1.27 1.27)
				)
				(justify mirror)
			)
		)
		(duplicate_pad_numbers_are_jumpers no)
		(zone
			(layer "B.Cu")
			(hatch none 0.5)
			(connect_pads
				(clearance 0)
			)
			(min_thickness 0.25)
			(keepout
				(tracks allowed)
				(vias allowed)
				(pads allowed)
				(copperpour allowed)
				(footprints not_allowed)
			)
			(placement
				(enabled no)
				(sheetname "")
			)
			(fill
				(thermal_gap 0.5)
				(thermal_bridge_width 0.5)
				(island_removal_mode 0)
			)
			(polygon
				(pts
					(arc
						(start 453.286368 -125.607064)
						(mid 433.286408 -125.607064)
						(end 453.286368 -125.607064)
					)
				)
			)
		)
	)
	(footprint ""
		(layer "B.Cu")
		(at 382.016 -205.101952 -90)
		(property "Reference" "R420"
			(at 0 0 90)
			(layer "B.SilkS")
			(hide yes)
			(effects
				(font
					(size 1.27 1.27)
				)
				(justify mirror)
			)
		)
		(property "Value" ""
			(at 0 0 90)
			(layer "B.Fab")
			(effects
				(font
					(size 1.27 1.27)
				)
				(justify mirror)
			)
		)
		(duplicate_pad_numbers_are_jumpers no)
		(fp_line
			(start -0.7874 0.4064)
			(end 0.7874 0.4064)
			(stroke
				(width 0.1524)
				(type default)
			)
			(layer "B.SilkS")
		)
		(fp_line
			(start 0.7874 0.4064)
			(end 0.7874 -0.4064)
			(stroke
				(width 0.1524)
				(type default)
			)
			(layer "B.SilkS")
		)
		(fp_line
			(start -0.7874 -0.4064)
			(end -0.7874 0.4064)
			(stroke
				(width 0.1524)
				(type default)
			)
			(layer "B.SilkS")
		)
		(fp_line
			(start 0.7874 -0.4064)
			(end -0.7874 -0.4064)
			(stroke
				(width 0.1524)
				(type default)
			)
			(layer "B.SilkS")
		)
		(fp_line
			(start -0.67945 0.3048)
			(end -0.120396 0.3048)
			(stroke
				(width 0.1)
				(type default)
			)
			(layer "B.Fab")
		)
		(fp_line
			(start -0.120396 0.3048)
			(end -0.120396 0.2794)
			(stroke
				(width 0.1)
				(type default)
			)
			(layer "B.Fab")
		)
		(fp_line
			(start 0.12065 0.3048)
			(end 0.67945 0.3048)
			(stroke
				(width 0.1)
				(type default)
			)
			(layer "B.Fab")
		)
		(fp_line
			(start 0.67945 0.3048)
			(end 0.67945 -0.305054)
			(stroke
				(width 0.1)
				(type default)
			)
			(layer "B.Fab")
		)
		(fp_line
			(start -0.120396 0.2794)
			(end 0.12065 0.2794)
			(stroke
				(width 0.1)
				(type default)
			)
			(layer "B.Fab")
		)
		(fp_line
			(start 0.12065 0.2794)
			(end 0.12065 0.3048)
			(stroke
				(width 0.1)
				(type default)
			)
			(layer "B.Fab")
		)
		(fp_line
			(start -0.12065 -0.2794)
			(end -0.12065 -0.3048)
			(stroke
				(width 0.1)
				(type default)
			)
			(layer "B.Fab")
		)
		(fp_line
			(start 0.12065 -0.2794)
			(end -0.12065 -0.2794)
			(stroke
				(width 0.1)
				(type default)
			)
			(layer "B.Fab")
		)
		(fp_line
			(start -0.67945 -0.3048)
			(end -0.67945 0.3048)
			(stroke
				(width 0.1)
				(type default)
			)
			(layer "B.Fab")
		)
		(fp_line
			(start -0.12065 -0.3048)
			(end -0.67945 -0.3048)
			(stroke
				(width 0.1)
				(type default)
			)
			(layer "B.Fab")
		)
		(fp_line
			(start 0.12065 -0.305054)
			(end 0.12065 -0.2794)
			(stroke
				(width 0.1)
				(type default)
			)
			(layer "B.Fab")
		)
		(fp_line
			(start 0.67945 -0.305054)
			(end 0.12065 -0.305054)
			(stroke
				(width 0.1)
				(type default)
			)
			(layer "B.Fab")
		)
		(pad "1" smd circle
			(at 0.40005 0 90)
			(size 0 0)
			(layers "B.Cu" "B.Mask" "B.Paste")
			(net "PVDD11_S3_P0")
		)
		(pad "2" smd circle
			(at -0.40005 0 90)
			(size 0 0)
			(layers "B.Cu" "B.Mask" "B.Paste")
			(net "I3C_1_SPD_DDRGL_CPU0_R_SDA")
		)
	)
	(footprint ""
		(layer "B.Cu")
		(at 138.34872 -35.304222 -90)
		(property "Reference" "C6044"
			(at 0 0 90)
			(layer "B.SilkS")
			(hide yes)
			(effects
				(font
					(size 1.27 1.27)
				)
				(justify mirror)
			)
		)
		(property "Value" ""
			(at 0 0 90)
			(layer "B.Fab")
			(effects
				(font
					(size 1.27 1.27)
				)
				(justify mirror)
			)
		)
		(duplicate_pad_numbers_are_jumpers no)
		(fp_line
			(start -0.7874 0.4064)
			(end 0.7874 0.4064)
			(stroke
				(width 0.1524)
				(type default)
			)
			(layer "B.SilkS")
		)
		(fp_line
			(start 0.7874 0.4064)
			(end 0.7874 -0.4064)
			(stroke
				(width 0.1524)
				(type default)
			)
			(layer "B.SilkS")
		)
		(fp_line
			(start -0.7874 -0.4064)
			(end -0.7874 0.4064)
			(stroke
				(width 0.1524)
				(type default)
			)
			(layer "B.SilkS")
		)
		(fp_line
			(start 0.7874 -0.4064)
			(end -0.7874 -0.4064)
			(stroke
				(width 0.1524)
				(type default)
			)
			(layer "B.SilkS")
		)
		(fp_line
			(start -0.67945 0.3048)
			(end -0.120396 0.3048)
			(stroke
				(width 0.1)
				(type default)
			)
			(layer "B.Fab")
		)
		(fp_line
			(start -0.120396 0.3048)
			(end -0.120396 0.2794)
			(stroke
				(width 0.1)
				(type default)
			)
			(layer "B.Fab")
		)
		(fp_line
			(start 0.12065 0.3048)
			(end 0.67945 0.3048)
			(stroke
				(width 0.1)
				(type default)
			)
			(layer "B.Fab")
		)
		(fp_line
			(start 0.67945 0.3048)
			(end 0.67945 -0.305054)
			(stroke
				(width 0.1)
				(type default)
			)
			(layer "B.Fab")
		)
		(fp_line
			(start -0.120396 0.2794)
			(end 0.12065 0.2794)
			(stroke
				(width 0.1)
				(type default)
			)
			(layer "B.Fab")
		)
		(fp_line
			(start 0.12065 0.2794)
			(end 0.12065 0.3048)
			(stroke
				(width 0.1)
				(type default)
			)
			(layer "B.Fab")
		)
		(fp_line
			(start -0.12065 -0.2794)
			(end -0.12065 -0.3048)
			(stroke
				(width 0.1)
				(type default)
			)
			(layer "B.Fab")
		)
		(fp_line
			(start 0.12065 -0.2794)
			(end -0.12065 -0.2794)
			(stroke
				(width 0.1)
				(type default)
			)
			(layer "B.Fab")
		)
		(fp_line
			(start -0.67945 -0.3048)
			(end -0.67945 0.3048)
			(stroke
				(width 0.1)
				(type default)
			)
			(layer "B.Fab")
		)
		(fp_line
			(start -0.12065 -0.3048)
			(end -0.67945 -0.3048)
			(stroke
				(width 0.1)
				(type default)
			)
			(layer "B.Fab")
		)
		(fp_line
			(start 0.12065 -0.305054)
			(end 0.12065 -0.2794)
			(stroke
				(width 0.1)
				(type default)
			)
			(layer "B.Fab")
		)
		(fp_line
			(start 0.67945 -0.305054)
			(end 0.12065 -0.305054)
			(stroke
				(width 0.1)
				(type default)
			)
			(layer "B.Fab")
		)
		(pad "1" smd circle
			(at 0.40005 0 90)
			(size 0 0)
			(layers "B.Cu" "B.Mask" "B.Paste")
			(net "P3V3_AUX_CPU0_USB_AVDD33")
		)
		(pad "2" smd circle
			(at -0.40005 0 90)
			(size 0 0)
			(layers "B.Cu" "B.Mask" "B.Paste")
			(net "GND")
		)
	)
	(footprint ""
		(layer "B.Cu")
		(at 149.597872 -64.04229 90)
		(property "Reference" "R13"
			(at 0 0 90)
			(layer "B.SilkS")
			(hide yes)
			(effects
				(font
					(size 1.27 1.27)
				)
				(justify mirror)
			)
		)
		(property "Value" ""
			(at 0 0 90)
			(layer "B.Fab")
			(effects
				(font
					(size 1.27 1.27)
				)
				(justify mirror)
			)
		)
		(duplicate_pad_numbers_are_jumpers no)
		(fp_line
			(start 0.7874 -0.4064)
			(end -0.7874 -0.4064)
			(stroke
				(width 0.1524)
				(type default)
			)
			(layer "B.SilkS")
		)
		(fp_line
			(start -0.7874 -0.4064)
			(end -0.7874 0.4064)
			(stroke
				(width 0.1524)
				(type default)
			)
			(layer "B.SilkS")
		)
		(fp_line
			(start 0.7874 0.4064)
			(end 0.7874 -0.4064)
			(stroke
				(width 0.1524)
				(type default)
			)
			(layer "B.SilkS")
		)
		(fp_line
			(start -0.7874 0.4064)
			(end 0.7874 0.4064)
			(stroke
				(width 0.1524)
				(type default)
			)
			(layer "B.SilkS")
		)
		(fp_line
			(start 0.67945 -0.305054)
			(end 0.12065 -0.305054)
			(stroke
				(width 0.1)
				(type default)
			)
			(layer "B.Fab")
		)
		(fp_line
			(start 0.12065 -0.305054)
			(end 0.12065 -0.2794)
			(stroke
				(width 0.1)
				(type default)
			)
			(layer "B.Fab")
		)
		(fp_line
			(start -0.12065 -0.3048)
			(end -0.67945 -0.3048)
			(stroke
				(width 0.1)
				(type default)
			)
			(layer "B.Fab")
		)
		(fp_line
			(start -0.67945 -0.3048)
			(end -0.67945 0.3048)
			(stroke
				(width 0.1)
				(type default)
			)
			(layer "B.Fab")
		)
		(fp_line
			(start 0.12065 -0.2794)
			(end -0.12065 -0.2794)
			(stroke
				(width 0.1)
				(type default)
			)
			(layer "B.Fab")
		)
		(fp_line
			(start -0.12065 -0.2794)
			(end -0.12065 -0.3048)
			(stroke
				(width 0.1)
				(type default)
			)
			(layer "B.Fab")
		)
		(fp_line
			(start 0.12065 0.2794)
			(end 0.12065 0.3048)
			(stroke
				(width 0.1)
				(type default)
			)
			(layer "B.Fab")
		)
		(fp_line
			(start -0.120396 0.2794)
			(end 0.12065 0.2794)
			(stroke
				(width 0.1)
				(type default)
			)
			(layer "B.Fab")
		)
		(fp_line
			(start 0.67945 0.3048)
			(end 0.67945 -0.305054)
			(stroke
				(width 0.1)
				(type default)
			)
			(layer "B.Fab")
		)
		(fp_line
			(start 0.12065 0.3048)
			(end 0.67945 0.3048)
			(stroke
				(width 0.1)
				(type default)
			)
			(layer "B.Fab")
		)
		(fp_line
			(start -0.120396 0.3048)
			(end -0.120396 0.2794)
			(stroke
				(width 0.1)
				(type default)
			)
			(layer "B.Fab")
		)
		(fp_line
			(start -0.67945 0.3048)
			(end -0.120396 0.3048)
			(stroke
				(width 0.1)
				(type default)
			)
			(layer "B.Fab")
		)
		(pad "1" smd circle
			(at 0.40005 0 270)
			(size 0 0)
			(layers "B.Cu" "B.Mask" "B.Paste")
			(net "JTAG_PLD_TDO")
		)
		(pad "2" smd circle
			(at -0.40005 0 270)
			(size 0 0)
			(layers "B.Cu" "B.Mask" "B.Paste")
			(net "JTAG_SCM_PLD_TDO")
		)
	)
)
